(kicad_pcb
	(version 20260206)
	(generator "pcbnew")
	(generator_version "10.0")
	(general
		(thickness 1.6)
		(legacy_teardrops no)
	)
	(paper "A4")
	(title_block
		(title "03242023_DA0F0TMBIJ0_F0T_Motherboard_J_brd_V01_OCP.brd")
		(comment 1 "Grand Teton / footprint 1682 of 6105 (U1), pads 3679-3790 of 4677")
	)
	(layers
		(0 "F.Cu" signal "TOP")
		(4 "In1.Cu" signal "GND")
		(6 "In2.Cu" signal "IN1")
		(8 "In3.Cu" signal "GND1")
		(10 "In4.Cu" signal "IN2")
		(12 "In5.Cu" signal "GND2")
		(14 "In6.Cu" signal "IN3")
		(16 "In7.Cu" signal "GND3")
		(18 "In8.Cu" signal "VCC")
		(20 "In9.Cu" signal "VCC1")
		(22 "In10.Cu" signal "GND4")
		(24 "In11.Cu" signal "IN4")
		(26 "In12.Cu" signal "GND5")
		(28 "In13.Cu" signal "IN5")
		(30 "In14.Cu" signal "GND6")
		(32 "In15.Cu" signal "IN6")
		(34 "In16.Cu" signal "GND7")
		(2 "B.Cu" signal "BOTTOM")
		(9 "F.Adhes" user "F.Adhesive")
		(11 "B.Adhes" user "B.Adhesive")
		(13 "F.Paste" user "Package Geometry/Pastemask Top")
		(15 "B.Paste" user "Package Geometry/Pastemask Bottom")
		(5 "F.SilkS" user "Ref Des/Silkscreen Top")
		(7 "B.SilkS" user "Ref Des/Silkscreen Bottom")
		(1 "F.Mask" user "Board Geometry/Soldermask Top")
		(3 "B.Mask" user "Board Geometry/Soldermask Bottom")
		(17 "Dwgs.User" user "User.Drawings")
		(19 "Cmts.User" user "User.Comments")
		(21 "Eco1.User" user "User.Eco1")
		(23 "Eco2.User" user "User.Eco2")
		(25 "Edge.Cuts" user "Board Geometry/Outline")
		(27 "Margin" user)
		(31 "F.CrtYd" user "Package Geometry/Place Bound Top")
		(29 "B.CrtYd" user "Package Geometry/Place Bound Bottom")
		(35 "F.Fab" user "Ref Des/Assembly Top")
		(33 "B.Fab" user "Ref Des/Assembly Bottom")
	)
	(footprint ""
		(layer "F.Cu")
		(at 111.93018 -251.76988 90)
		(property "Reference" "U1"
			(at -74.913236 41.548812 0)
			(unlocked yes)
			(layer "F.SilkS")
			(effects
				(font
					(size 1.6002 1.1938)
					(thickness 0.1524)
				)
				(justify left)
			)
		)
		(property "Value" ""
			(at 0 0 90)
			(layer "F.Fab")
			(effects
				(font
					(size 1.27 1.27)
				)
			)
		)
		(duplicate_pad_numbers_are_jumpers no)
		(pad "EH71" smd circle
			(at 21.147278 23.314914 270)
			(size 0.4318 0.4318)
			(layers "F.Cu" "F.Mask" "F.Paste")
			(net "M_E_CPU1_SA_DQ<11>")
		)
		(pad "EH73" smd circle
			(at 22.77491 23.314914 270)
			(size 0.4318 0.4318)
			(layers "F.Cu" "F.Mask" "F.Paste")
			(net "GND")
		)
		(pad "EH75" smd circle
			(at 24.402796 23.314914 270)
			(size 0.4318 0.4318)
			(layers "F.Cu" "F.Mask" "F.Paste")
			(net "M_F_CPU1_SA_DQ<6>")
		)
		(pad "EH77" smd circle
			(at 26.030682 23.314914 270)
			(size 0.4318 0.4318)
			(layers "F.Cu" "F.Mask" "F.Paste")
			(net "M_F_CPU1_SA_DQ<1>")
		)
		(pad "EH79" smd circle
			(at 27.658314 23.314914 270)
			(size 0.4318 0.4318)
			(layers "F.Cu" "F.Mask" "F.Paste")
			(net "GND")
		)
		(pad "EH81" smd circle
			(at 29.2862 23.314914 270)
			(size 0.4318 0.4318)
			(layers "F.Cu" "F.Mask" "F.Paste")
			(net "GND")
		)
		(pad "EH83" smd circle
			(at 30.914086 23.314914 270)
			(size 0.4318 0.4318)
			(layers "F.Cu" "F.Mask" "F.Paste")
			(net "GND")
		)
		(pad "EH85" smd circle
			(at 32.541718 23.314914 270)
			(size 0.4318 0.4318)
			(layers "F.Cu" "F.Mask" "F.Paste")
			(net "Net_749")
		)
		(pad "EH87" smd circle
			(at 34.169604 23.314914 270)
			(size 0.4318 0.4318)
			(layers "F.Cu" "F.Mask" "F.Paste")
			(net "Net_707")
		)
		(pad "EH89" smd oval
			(at 35.797236 23.314914 315)
			(size 0.381 0.4826)
			(drill
				(offset 0 -0.0508)
			)
			(layers "F.Cu" "F.Mask" "F.Paste")
			(net "P5E_CPU1_PE3_RX_DN<0>")
		)
		(pad "EJ3" smd oval
			(at -35.797236 23.675086 225)
			(size 0.381 0.4826)
			(drill
				(offset 0 -0.0508)
			)
			(layers "F.Cu" "F.Mask" "F.Paste")
			(net "UPI_CPU0_CPU1_P0P1_DP<0>")
		)
		(pad "EJ5" smd circle
			(at -34.169604 23.675086 270)
			(size 0.4318 0.4318)
			(layers "F.Cu" "F.Mask" "F.Paste")
			(net "M_G_CPU1_SB_DQ<29>")
		)
		(pad "EJ7" smd circle
			(at -32.541718 23.675086 270)
			(size 0.4318 0.4318)
			(layers "F.Cu" "F.Mask" "F.Paste")
			(net "GND")
		)
		(pad "EJ9" smd circle
			(at -30.914086 23.675086 270)
			(size 0.4318 0.4318)
			(layers "F.Cu" "F.Mask" "F.Paste")
			(net "GND")
		)
		(pad "EJ11" smd circle
			(at -29.2862 23.675086 270)
			(size 0.4318 0.4318)
			(layers "F.Cu" "F.Mask" "F.Paste")
			(net "GND")
		)
		(pad "EJ13" smd circle
			(at -27.658314 23.675086 270)
			(size 0.4318 0.4318)
			(layers "F.Cu" "F.Mask" "F.Paste")
			(net "GND")
		)
		(pad "EJ15" smd circle
			(at -26.030682 23.675086 270)
			(size 0.4318 0.4318)
			(layers "F.Cu" "F.Mask" "F.Paste")
			(net "PVCCFA_EHV_FIVRA_CPU1")
		)
		(pad "EJ17" smd circle
			(at -24.402796 23.675086 270)
			(size 0.4318 0.4318)
			(layers "F.Cu" "F.Mask" "F.Paste")
			(net "GND")
		)
		(pad "EJ19" smd circle
			(at -22.77491 23.675086 270)
			(size 0.4318 0.4318)
			(layers "F.Cu" "F.Mask" "F.Paste")
			(net "GND")
		)
		(pad "EJ21" smd circle
			(at -21.147278 23.675086 270)
			(size 0.4318 0.4318)
			(layers "F.Cu" "F.Mask" "F.Paste")
			(net "M_F_CPU1_SB_DQS_DN<6>")
		)
		(pad "EJ23" smd circle
			(at -19.519392 23.675086 270)
			(size 0.4318 0.4318)
			(layers "F.Cu" "F.Mask" "F.Paste")
			(net "GND")
		)
		(pad "EJ25" smd circle
			(at -17.89176 23.675086 270)
			(size 0.4318 0.4318)
			(layers "F.Cu" "F.Mask" "F.Paste")
			(net "GND")
		)
		(pad "EJ27" smd circle
			(at -16.263874 23.675086 270)
			(size 0.4318 0.4318)
			(layers "F.Cu" "F.Mask" "F.Paste")
			(net "M_E_CPU1_SB_DQS_DN<5>")
		)
		(pad "EJ29" smd circle
			(at -14.635988 23.675086 270)
			(size 0.4318 0.4318)
			(layers "F.Cu" "F.Mask" "F.Paste")
			(net "GND")
		)
		(pad "EJ31" smd circle
			(at -13.008356 23.675086 270)
			(size 0.4318 0.4318)
			(layers "F.Cu" "F.Mask" "F.Paste")
			(net "GND")
		)
		(pad "EJ33" smd circle
			(at -11.380724 23.675086 270)
			(size 0.4318 0.4318)
			(layers "F.Cu" "F.Mask" "F.Paste")
			(net "M_F_CPU1_SB_DQS_DN<4>")
		)
		(pad "EJ35" smd circle
			(at -9.752838 23.675086 270)
			(size 0.4318 0.4318)
			(layers "F.Cu" "F.Mask" "F.Paste")
			(net "GND")
		)
		(pad "EJ37" smd circle
			(at -8.124952 23.675086 270)
			(size 0.4318 0.4318)
			(layers "F.Cu" "F.Mask" "F.Paste")
			(net "GND")
		)
		(pad "EJ39" smd circle
			(at -6.49732 23.675086 270)
			(size 0.4318 0.4318)
			(layers "F.Cu" "F.Mask" "F.Paste")
			(net "M_F_CPU1_SB_PAR")
		)
		(pad "EJ41" smd circle
			(at -4.869434 23.675086 270)
			(size 0.4318 0.4318)
			(layers "F.Cu" "F.Mask" "F.Paste")
			(net "GND")
		)
		(pad "EJ43" smd circle
			(at -3.241802 23.675086 270)
			(size 0.4318 0.4318)
			(layers "F.Cu" "F.Mask" "F.Paste")
			(net "GND")
		)
		(pad "EJ45" smd circle
			(at -1.613916 23.675086 270)
			(size 0.4318 0.4318)
			(layers "F.Cu" "F.Mask" "F.Paste")
			(net "M_E_CPU1_CLK_DN<0>")
		)
		(pad "EJ48" smd circle
			(at 2.427732 23.784814 270)
			(size 0.4318 0.4318)
			(layers "F.Cu" "F.Mask" "F.Paste")
			(net "GND")
		)
		(pad "EJ50" smd circle
			(at 4.055618 23.784814 270)
			(size 0.4318 0.4318)
			(layers "F.Cu" "F.Mask" "F.Paste")
			(net "GND")
		)
		(pad "EJ52" smd circle
			(at 5.68325 23.784814 270)
			(size 0.4318 0.4318)
			(layers "F.Cu" "F.Mask" "F.Paste")
			(net "M_F_CPU1_SA_CA<1>")
		)
		(pad "EJ54" smd circle
			(at 7.311136 23.784814 270)
			(size 0.4318 0.4318)
			(layers "F.Cu" "F.Mask" "F.Paste")
			(net "GND")
		)
		(pad "EJ56" smd circle
			(at 8.939022 23.784814 270)
			(size 0.4318 0.4318)
			(layers "F.Cu" "F.Mask" "F.Paste")
			(net "GND")
		)
		(pad "EJ58" smd circle
			(at 10.566654 23.784814 270)
			(size 0.4318 0.4318)
			(layers "F.Cu" "F.Mask" "F.Paste")
			(net "M_F_CPU1_SA_DQS_DN<9>")
		)
		(pad "EJ60" smd circle
			(at 12.19454 23.784814 270)
			(size 0.4318 0.4318)
			(layers "F.Cu" "F.Mask" "F.Paste")
			(net "GND")
		)
		(pad "EJ62" smd circle
			(at 13.822426 23.784814 270)
			(size 0.4318 0.4318)
			(layers "F.Cu" "F.Mask" "F.Paste")
			(net "GND")
		)
		(pad "EJ64" smd circle
			(at 15.450058 23.784814 270)
			(size 0.4318 0.4318)
			(layers "F.Cu" "F.Mask" "F.Paste")
			(net "M_F_CPU1_SA_DQS_DN<7>")
		)
		(pad "EJ66" smd circle
			(at 17.07769 23.784814 270)
			(size 0.4318 0.4318)
			(layers "F.Cu" "F.Mask" "F.Paste")
			(net "GND")
		)
		(pad "EJ68" smd circle
			(at 18.705576 23.784814 270)
			(size 0.4318 0.4318)
			(layers "F.Cu" "F.Mask" "F.Paste")
			(net "GND")
		)
		(pad "EJ70" smd circle
			(at 20.333462 23.784814 270)
			(size 0.4318 0.4318)
			(layers "F.Cu" "F.Mask" "F.Paste")
			(net "M_E_CPU1_SA_DQS_DN<6>")
		)
		(pad "EJ72" smd circle
			(at 21.961094 23.784814 270)
			(size 0.4318 0.4318)
			(layers "F.Cu" "F.Mask" "F.Paste")
			(net "GND")
		)
		(pad "EJ74" smd circle
			(at 23.58898 23.784814 270)
			(size 0.4318 0.4318)
			(layers "F.Cu" "F.Mask" "F.Paste")
			(net "GND")
		)
		(pad "EJ76" smd circle
			(at 25.216612 23.784814 270)
			(size 0.4318 0.4318)
			(layers "F.Cu" "F.Mask" "F.Paste")
			(net "M_F_CPU1_SA_DQS_DN<5>")
		)
		(pad "EJ78" smd circle
			(at 26.844498 23.784814 270)
			(size 0.4318 0.4318)
			(layers "F.Cu" "F.Mask" "F.Paste")
			(net "GND")
		)
		(pad "EJ80" smd circle
			(at 28.472384 23.784814 270)
			(size 0.4318 0.4318)
			(layers "F.Cu" "F.Mask" "F.Paste")
			(net "GND")
		)
		(pad "EJ82" smd circle
			(at 30.100016 23.784814 270)
			(size 0.4318 0.4318)
			(layers "F.Cu" "F.Mask" "F.Paste")
			(net "GND")
		)
		(pad "EJ84" smd circle
			(at 31.727902 23.784814 270)
			(size 0.4318 0.4318)
			(layers "F.Cu" "F.Mask" "F.Paste")
			(net "PVCCFA_EHV_FIVRA_CPU1")
		)
		(pad "EJ86" smd circle
			(at 33.355534 23.784814 270)
			(size 0.4318 0.4318)
			(layers "F.Cu" "F.Mask" "F.Paste")
			(net "Net_731")
		)
		(pad "EJ88" smd oval
			(at 34.98342 23.784814 315)
			(size 0.381 0.4826)
			(drill
				(offset 0 -0.0508)
			)
			(layers "F.Cu" "F.Mask" "F.Paste")
			(net "GND")
		)
		(pad "EJ90" smd oval
			(at 36.611306 23.784814 315)
			(size 0.381 0.4826)
			(drill
				(offset 0 -0.0508)
			)
			(layers "F.Cu" "F.Mask" "F.Paste")
			(net "P5E_CPU1_PE3_RX_DP<0>")
		)
		(pad "EK2" smd oval
			(at -36.611306 24.144986 225)
			(size 0.381 0.4826)
			(drill
				(offset 0 -0.0508)
			)
			(layers "F.Cu" "F.Mask" "F.Paste")
			(net "GND")
		)
		(pad "EK4" smd oval
			(at -34.98342 24.144986 225)
			(size 0.381 0.4826)
			(drill
				(offset 0 -0.0508)
			)
			(layers "F.Cu" "F.Mask" "F.Paste")
			(net "GND")
		)
		(pad "EK6" smd circle
			(at -33.355534 24.144986 270)
			(size 0.4318 0.4318)
			(layers "F.Cu" "F.Mask" "F.Paste")
			(net "M_G_CPU1_SB_DQ<28>")
		)
		(pad "EK8" smd circle
			(at -31.727902 24.144986 270)
			(size 0.4318 0.4318)
			(layers "F.Cu" "F.Mask" "F.Paste")
			(net "M_G_CPU1_SB_DQ<24>")
		)
		(pad "EK10" smd circle
			(at -30.100016 24.144986 270)
			(size 0.4318 0.4318)
			(layers "F.Cu" "F.Mask" "F.Paste")
			(net "GND")
		)
		(pad "EK12" smd circle
			(at -28.472384 24.144986 270)
			(size 0.4318 0.4318)
			(layers "F.Cu" "F.Mask" "F.Paste")
			(net "M_F_CPU1_SB_DQS_DP<2>")
		)
		(pad "EK14" smd circle
			(at -26.844498 24.144986 270)
			(size 0.4318 0.4318)
			(layers "F.Cu" "F.Mask" "F.Paste")
			(net "GND")
		)
		(pad "EK16" smd circle
			(at -25.216612 24.144986 270)
			(size 0.4318 0.4318)
			(layers "F.Cu" "F.Mask" "F.Paste")
			(net "GND")
		)
		(pad "EK18" smd circle
			(at -23.58898 24.144986 270)
			(size 0.4318 0.4318)
			(layers "F.Cu" "F.Mask" "F.Paste")
			(net "M_E_CPU1_SB_DQS_DN<3>")
		)
		(pad "EK20" smd circle
			(at -21.961094 24.144986 270)
			(size 0.4318 0.4318)
			(layers "F.Cu" "F.Mask" "F.Paste")
			(net "GND")
		)
		(pad "EK22" smd circle
			(at -20.333462 24.144986 270)
			(size 0.4318 0.4318)
			(layers "F.Cu" "F.Mask" "F.Paste")
			(net "GND")
		)
		(pad "EK24" smd circle
			(at -18.705576 24.144986 270)
			(size 0.4318 0.4318)
			(layers "F.Cu" "F.Mask" "F.Paste")
			(net "M_E_CPU1_SB_DQS_DN<2>")
		)
		(pad "EK26" smd circle
			(at -17.07769 24.144986 270)
			(size 0.4318 0.4318)
			(layers "F.Cu" "F.Mask" "F.Paste")
			(net "GND")
		)
		(pad "EK28" smd circle
			(at -15.450058 24.144986 270)
			(size 0.4318 0.4318)
			(layers "F.Cu" "F.Mask" "F.Paste")
			(net "GND")
		)
		(pad "EK30" smd circle
			(at -13.822426 24.144986 270)
			(size 0.4318 0.4318)
			(layers "F.Cu" "F.Mask" "F.Paste")
			(net "M_E_CPU1_SB_DQS_DN<1>")
		)
		(pad "EK32" smd circle
			(at -12.19454 24.144986 270)
			(size 0.4318 0.4318)
			(layers "F.Cu" "F.Mask" "F.Paste")
			(net "GND")
		)
		(pad "EK34" smd circle
			(at -10.566654 24.144986 270)
			(size 0.4318 0.4318)
			(layers "F.Cu" "F.Mask" "F.Paste")
			(net "GND")
		)
		(pad "EK36" smd circle
			(at -8.939022 24.144986 270)
			(size 0.4318 0.4318)
			(layers "F.Cu" "F.Mask" "F.Paste")
			(net "M_E_CPU1_SB_DQS_DN<9>")
		)
		(pad "EK38" smd circle
			(at -7.311136 24.144986 270)
			(size 0.4318 0.4318)
			(layers "F.Cu" "F.Mask" "F.Paste")
			(net "GND")
		)
		(pad "EK40" smd circle
			(at -5.68325 24.144986 270)
			(size 0.4318 0.4318)
			(layers "F.Cu" "F.Mask" "F.Paste")
			(net "GND")
		)
		(pad "EK42" smd circle
			(at -4.055618 24.144986 270)
			(size 0.4318 0.4318)
			(layers "F.Cu" "F.Mask" "F.Paste")
			(net "M_E_CPU1_SB_CA<6>")
		)
		(pad "EK44" smd circle
			(at -2.427732 24.144986 270)
			(size 0.4318 0.4318)
			(layers "F.Cu" "F.Mask" "F.Paste")
			(net "GND")
		)
		(pad "EK47" smd circle
			(at 1.613916 24.254714 270)
			(size 0.4318 0.4318)
			(layers "F.Cu" "F.Mask" "F.Paste")
			(net "GND")
		)
		(pad "EK49" smd circle
			(at 3.241802 24.254714 270)
			(size 0.4318 0.4318)
			(layers "F.Cu" "F.Mask" "F.Paste")
			(net "M_E_CPU1_SA_CA<2>")
		)
		(pad "EK51" smd circle
			(at 4.869434 24.254714 270)
			(size 0.4318 0.4318)
			(layers "F.Cu" "F.Mask" "F.Paste")
			(net "GND")
		)
		(pad "EK53" smd circle
			(at 6.49732 24.254714 270)
			(size 0.4318 0.4318)
			(layers "F.Cu" "F.Mask" "F.Paste")
			(net "GND")
		)
		(pad "EK55" smd circle
			(at 8.124952 24.254714 270)
			(size 0.4318 0.4318)
			(layers "F.Cu" "F.Mask" "F.Paste")
			(net "M_E_CPU1_SA_DQS_DP<4>")
		)
		(pad "EK57" smd circle
			(at 9.752838 24.254714 270)
			(size 0.4318 0.4318)
			(layers "F.Cu" "F.Mask" "F.Paste")
			(net "GND")
		)
		(pad "EK59" smd circle
			(at 11.380724 24.254714 270)
			(size 0.4318 0.4318)
			(layers "F.Cu" "F.Mask" "F.Paste")
			(net "GND")
		)
		(pad "EK61" smd circle
			(at 13.008356 24.254714 270)
			(size 0.4318 0.4318)
			(layers "F.Cu" "F.Mask" "F.Paste")
			(net "M_E_CPU1_SA_DQS_DN<3>")
		)
		(pad "EK63" smd circle
			(at 14.635988 24.254714 270)
			(size 0.4318 0.4318)
			(layers "F.Cu" "F.Mask" "F.Paste")
			(net "GND")
		)
		(pad "EK65" smd circle
			(at 16.263874 24.254714 270)
			(size 0.4318 0.4318)
			(layers "F.Cu" "F.Mask" "F.Paste")
			(net "GND")
		)
		(pad "EK67" smd circle
			(at 17.89176 24.254714 270)
			(size 0.4318 0.4318)
			(layers "F.Cu" "F.Mask" "F.Paste")
			(net "M_E_CPU1_SA_DQS_DN<2>")
		)
		(pad "EK69" smd circle
			(at 19.519392 24.254714 270)
			(size 0.4318 0.4318)
			(layers "F.Cu" "F.Mask" "F.Paste")
			(net "GND")
		)
		(pad "EK71" smd circle
			(at 21.147278 24.254714 270)
			(size 0.4318 0.4318)
			(layers "F.Cu" "F.Mask" "F.Paste")
			(net "GND")
		)
		(pad "EK73" smd circle
			(at 22.77491 24.254714 270)
			(size 0.4318 0.4318)
			(layers "F.Cu" "F.Mask" "F.Paste")
			(net "M_E_CPU1_SA_DQ<5>")
		)
		(pad "EK75" smd circle
			(at 24.402796 24.254714 270)
			(size 0.4318 0.4318)
			(layers "F.Cu" "F.Mask" "F.Paste")
			(net "GND")
		)
		(pad "EK77" smd circle
			(at 26.030682 24.254714 270)
			(size 0.4318 0.4318)
			(layers "F.Cu" "F.Mask" "F.Paste")
			(net "GND")
		)
		(pad "EK79" smd circle
			(at 27.658314 24.254714 270)
			(size 0.4318 0.4318)
			(layers "F.Cu" "F.Mask" "F.Paste")
			(net "GND")
		)
		(pad "EK81" smd circle
			(at 29.2862 24.254714 270)
			(size 0.4318 0.4318)
			(layers "F.Cu" "F.Mask" "F.Paste")
			(net "GND")
		)
		(pad "EK83" smd circle
			(at 30.914086 24.254714 270)
			(size 0.4318 0.4318)
			(layers "F.Cu" "F.Mask" "F.Paste")
			(net "GND")
		)
		(pad "EK85" smd circle
			(at 32.541718 24.254714 270)
			(size 0.4318 0.4318)
			(layers "F.Cu" "F.Mask" "F.Paste")
			(net "Net_725")
		)
		(pad "EK87" smd oval
			(at 34.169604 24.254714 315)
			(size 0.381 0.4826)
			(drill
				(offset 0 -0.0508)
			)
			(layers "F.Cu" "F.Mask" "F.Paste")
			(net "Net_730")
		)
		(pad "EK89" smd oval
			(at 35.797236 24.254714 315)
			(size 0.381 0.4826)
			(drill
				(offset 0 -0.0508)
			)
			(layers "F.Cu" "F.Mask" "F.Paste")
			(net "GND")
		)
		(pad "EL3" smd oval
			(at -35.797236 24.614886 225)
			(size 0.381 0.4826)
			(drill
				(offset 0 -0.0508)
			)
			(layers "F.Cu" "F.Mask" "F.Paste")
			(net "GND")
		)
		(pad "EL5" smd oval
			(at -34.169604 24.614886 225)
			(size 0.381 0.4826)
			(drill
				(offset 0 -0.0508)
			)
			(layers "F.Cu" "F.Mask" "F.Paste")
			(net "GND")
		)
		(pad "EL7" smd circle
			(at -32.541718 24.614886 270)
			(size 0.4318 0.4318)
			(layers "F.Cu" "F.Mask" "F.Paste")
			(net "GND")
		)
		(pad "EL9" smd circle
			(at -30.914086 24.614886 270)
			(size 0.4318 0.4318)
			(layers "F.Cu" "F.Mask" "F.Paste")
			(net "GND")
		)
		(pad "EL11" smd circle
			(at -29.2862 24.614886 270)
			(size 0.4318 0.4318)
			(layers "F.Cu" "F.Mask" "F.Paste")
			(net "M_F_CPU1_SB_DQ<20>")
		)
		(pad "EL13" smd circle
			(at -27.658314 24.614886 270)
			(size 0.4318 0.4318)
			(layers "F.Cu" "F.Mask" "F.Paste")
			(net "M_F_CPU1_SB_DQ<17>")
		)
		(pad "EL15" smd circle
			(at -26.030682 24.614886 270)
			(size 0.4318 0.4318)
			(layers "F.Cu" "F.Mask" "F.Paste")
			(net "GND")
		)
		(pad "EL17" smd circle
			(at -24.402796 24.614886 270)
			(size 0.4318 0.4318)
			(layers "F.Cu" "F.Mask" "F.Paste")
			(net "M_E_CPU1_SB_DQ<28>")
		)
		(pad "EL19" smd circle
			(at -22.77491 24.614886 270)
			(size 0.4318 0.4318)
			(layers "F.Cu" "F.Mask" "F.Paste")
			(net "M_E_CPU1_SB_DQ<25>")
		)
		(pad "EL21" smd circle
			(at -21.147278 24.614886 270)
			(size 0.4318 0.4318)
			(layers "F.Cu" "F.Mask" "F.Paste")
			(net "GND")
		)
		(pad "EL23" smd circle
			(at -19.519392 24.614886 270)
			(size 0.4318 0.4318)
			(layers "F.Cu" "F.Mask" "F.Paste")
			(net "M_E_CPU1_SB_DQ<20>")
		)
		(pad "EL25" smd circle
			(at -17.89176 24.614886 270)
			(size 0.4318 0.4318)
			(layers "F.Cu" "F.Mask" "F.Paste")
			(net "M_E_CPU1_SB_DQ<17>")
		)
		(pad "EL27" smd circle
			(at -16.263874 24.614886 270)
			(size 0.4318 0.4318)
			(layers "F.Cu" "F.Mask" "F.Paste")
			(net "GND")
		)
		(pad "EL29" smd circle
			(at -14.635988 24.614886 270)
			(size 0.4318 0.4318)
			(layers "F.Cu" "F.Mask" "F.Paste")
			(net "M_E_CPU1_SB_DQ<12>")
		)
	)
)
